# S9S_MB_2U (Grand Teton) — schematic netlist excerpt (pin names and nets, part order shuffled) for the footprints in the layout excerpt that follows; sources: Cadence DE-HDL packaged netlist, KiCad conversion of 03242023_DA0F0TMBIJ0_F0T_Motherboard_J_brd_V01_OCP.brd

PL66  Q_INDUCTOR  1.5UH/53A IND  pkg SMLF  page 259 : \1\ = SW_P3V3_AUX_SW ; \2\ = P3V3_AUX
R4499  Q_RES  4.7K 5% CHIP  pkg 0402LF  page 237 : A = P3V3 ; B = SMB_HOST_CLK_BUF_ISO_3V3AUX_S_2
C308  Q_CAP  22UF 4V 20% X6S  pkg C0402  page 77 : A = PVCCIN_CPU1 ; B = GND

(kicad_pcb
	(version 20260206)
	(generator "pcbnew")
	(generator_version "10.0")
	(general
		(thickness 1.6)
		(legacy_teardrops no)
	)
	(paper "A4")
	(title_block
		(title "03242023_DA0F0TMBIJ0_F0T_Motherboard_J_brd_V01_OCP.brd")
		(comment 1 "Grand Teton / footprints 1470-1472 of 6105")
	)
	(layers
		(0 "F.Cu" signal "TOP")
		(4 "In1.Cu" signal "GND")
		(6 "In2.Cu" signal "IN1")
		(8 "In3.Cu" signal "GND1")
		(10 "In4.Cu" signal "IN2")
		(12 "In5.Cu" signal "GND2")
		(14 "In6.Cu" signal "IN3")
		(16 "In7.Cu" signal "GND3")
		(18 "In8.Cu" signal "VCC")
		(20 "In9.Cu" signal "VCC1")
		(22 "In10.Cu" signal "GND4")
		(24 "In11.Cu" signal "IN4")
		(26 "In12.Cu" signal "GND5")
		(28 "In13.Cu" signal "IN5")
		(30 "In14.Cu" signal "GND6")
		(32 "In15.Cu" signal "IN6")
		(34 "In16.Cu" signal "GND7")
		(2 "B.Cu" signal "BOTTOM")
		(9 "F.Adhes" user "F.Adhesive")
		(11 "B.Adhes" user "B.Adhesive")
		(13 "F.Paste" user "Package Geometry/Pastemask Top")
		(15 "B.Paste" user "Package Geometry/Pastemask Bottom")
		(5 "F.SilkS" user "Ref Des/Silkscreen Top")
		(7 "B.SilkS" user "Ref Des/Silkscreen Bottom")
		(1 "F.Mask" user "Board Geometry/Soldermask Top")
		(3 "B.Mask" user "Board Geometry/Soldermask Bottom")
		(17 "Dwgs.User" user "User.Drawings")
		(19 "Cmts.User" user "User.Comments")
		(21 "Eco1.User" user "User.Eco1")
		(23 "Eco2.User" user "User.Eco2")
		(25 "Edge.Cuts" user "Board Geometry/Outline")
		(27 "Margin" user)
		(31 "F.CrtYd" user "Package Geometry/Place Bound Top")
		(29 "B.CrtYd" user "Package Geometry/Place Bound Bottom")
		(35 "F.Fab" user "Ref Des/Assembly Top")
		(33 "B.Fab" user "Ref Des/Assembly Bottom")
	)
	(footprint ""
		(layer "F.Cu")
		(at 259.021326 -131.502912)
		(property "Reference" "R4499"
			(at 0 0 0)
			(layer "F.SilkS")
			(hide yes)
			(effects
				(font
					(size 1.27 1.27)
				)
			)
		)
		(property "Value" ""
			(at 0 0 0)
			(layer "F.Fab")
			(effects
				(font
					(size 1.27 1.27)
				)
			)
		)
		(duplicate_pad_numbers_are_jumpers no)
		(fp_line
			(start -0.7874 -0.4064)
			(end 0.7874 -0.4064)
			(stroke
				(width 0.1524)
				(type default)
			)
			(layer "F.SilkS")
		)
		(fp_line
			(start -0.7874 0.4064)
			(end -0.7874 -0.4064)
			(stroke
				(width 0.1524)
				(type default)
			)
			(layer "F.SilkS")
		)
		(fp_line
			(start 0.7874 -0.4064)
			(end 0.7874 0.4064)
			(stroke
				(width 0.1524)
				(type default)
			)
			(layer "F.SilkS")
		)
		(fp_line
			(start 0.7874 0.4064)
			(end -0.7874 0.4064)
			(stroke
				(width 0.1524)
				(type default)
			)
			(layer "F.SilkS")
		)
		(fp_line
			(start -0.67945 -0.305054)
			(end -0.12065 -0.305054)
			(stroke
				(width 0.1)
				(type default)
			)
			(layer "F.Fab")
		)
		(fp_line
			(start -0.67945 0.3048)
			(end -0.67945 -0.305054)
			(stroke
				(width 0.1)
				(type default)
			)
			(layer "F.Fab")
		)
		(fp_line
			(start -0.12065 -0.305054)
			(end -0.12065 -0.2794)
			(stroke
				(width 0.1)
				(type default)
			)
			(layer "F.Fab")
		)
		(fp_line
			(start -0.12065 -0.2794)
			(end 0.12065 -0.2794)
			(stroke
				(width 0.1)
				(type default)
			)
			(layer "F.Fab")
		)
		(fp_line
			(start -0.12065 0.2794)
			(end -0.12065 0.3048)
			(stroke
				(width 0.1)
				(type default)
			)
			(layer "F.Fab")
		)
		(fp_line
			(start -0.12065 0.3048)
			(end -0.67945 0.3048)
			(stroke
				(width 0.1)
				(type default)
			)
			(layer "F.Fab")
		)
		(fp_line
			(start 0.120396 0.2794)
			(end -0.12065 0.2794)
			(stroke
				(width 0.1)
				(type default)
			)
			(layer "F.Fab")
		)
		(fp_line
			(start 0.120396 0.3048)
			(end 0.120396 0.2794)
			(stroke
				(width 0.1)
				(type default)
			)
			(layer "F.Fab")
		)
		(fp_line
			(start 0.12065 -0.3048)
			(end 0.67945 -0.3048)
			(stroke
				(width 0.1)
				(type default)
			)
			(layer "F.Fab")
		)
		(fp_line
			(start 0.12065 -0.2794)
			(end 0.12065 -0.3048)
			(stroke
				(width 0.1)
				(type default)
			)
			(layer "F.Fab")
		)
		(fp_line
			(start 0.67945 -0.3048)
			(end 0.67945 0.3048)
			(stroke
				(width 0.1)
				(type default)
			)
			(layer "F.Fab")
		)
		(fp_line
			(start 0.67945 0.3048)
			(end 0.120396 0.3048)
			(stroke
				(width 0.1)
				(type default)
			)
			(layer "F.Fab")
		)
		(pad "1" smd circle
			(at -0.40005 0)
			(size 0 0)
			(layers "F.Cu" "F.Mask" "F.Paste")
			(net "P3V3")
		)
		(pad "2" smd circle
			(at 0.40005 0)
			(size 0 0)
			(layers "F.Cu" "F.Mask" "F.Paste")
			(net "SMB_HOST_CLK_BUF_ISO_3V3AUX_S_2")
		)
	)
	(footprint ""
		(layer "F.Cu")
		(at 116.561616 -258.72694 90)
		(property "Reference" "C308"
			(at 0 0 90)
			(layer "F.SilkS")
			(hide yes)
			(effects
				(font
					(size 1.27 1.27)
				)
			)
		)
		(property "Value" ""
			(at 0 0 90)
			(layer "F.Fab")
			(effects
				(font
					(size 1.27 1.27)
				)
			)
		)
		(duplicate_pad_numbers_are_jumpers no)
		(fp_line
			(start 0.7874 -0.4064)
			(end 0.7874 0.4064)
			(stroke
				(width 0.1524)
				(type default)
			)
			(layer "F.SilkS")
		)
		(fp_line
			(start -0.7874 -0.4064)
			(end 0.7874 -0.4064)
			(stroke
				(width 0.1524)
				(type default)
			)
			(layer "F.SilkS")
		)
		(fp_line
			(start 0.7874 0.4064)
			(end -0.7874 0.4064)
			(stroke
				(width 0.1524)
				(type default)
			)
			(layer "F.SilkS")
		)
		(fp_line
			(start -0.7874 0.4064)
			(end -0.7874 -0.4064)
			(stroke
				(width 0.1524)
				(type default)
			)
			(layer "F.SilkS")
		)
		(fp_line
			(start -0.12065 -0.305054)
			(end -0.12065 -0.2794)
			(stroke
				(width 0.1)
				(type default)
			)
			(layer "F.Fab")
		)
		(fp_line
			(start -0.67945 -0.305054)
			(end -0.12065 -0.305054)
			(stroke
				(width 0.1)
				(type default)
			)
			(layer "F.Fab")
		)
		(fp_line
			(start 0.67945 -0.3048)
			(end 0.67945 0.3048)
			(stroke
				(width 0.1)
				(type default)
			)
			(layer "F.Fab")
		)
		(fp_line
			(start 0.12065 -0.3048)
			(end 0.67945 -0.3048)
			(stroke
				(width 0.1)
				(type default)
			)
			(layer "F.Fab")
		)
		(fp_line
			(start 0.12065 -0.2794)
			(end 0.12065 -0.3048)
			(stroke
				(width 0.1)
				(type default)
			)
			(layer "F.Fab")
		)
		(fp_line
			(start -0.12065 -0.2794)
			(end 0.12065 -0.2794)
			(stroke
				(width 0.1)
				(type default)
			)
			(layer "F.Fab")
		)
		(fp_line
			(start 0.120396 0.2794)
			(end -0.12065 0.2794)
			(stroke
				(width 0.1)
				(type default)
			)
			(layer "F.Fab")
		)
		(fp_line
			(start -0.12065 0.2794)
			(end -0.12065 0.3048)
			(stroke
				(width 0.1)
				(type default)
			)
			(layer "F.Fab")
		)
		(fp_line
			(start 0.67945 0.3048)
			(end 0.120396 0.3048)
			(stroke
				(width 0.1)
				(type default)
			)
			(layer "F.Fab")
		)
		(fp_line
			(start 0.120396 0.3048)
			(end 0.120396 0.2794)
			(stroke
				(width 0.1)
				(type default)
			)
			(layer "F.Fab")
		)
		(fp_line
			(start -0.12065 0.3048)
			(end -0.67945 0.3048)
			(stroke
				(width 0.1)
				(type default)
			)
			(layer "F.Fab")
		)
		(fp_line
			(start -0.67945 0.3048)
			(end -0.67945 -0.305054)
			(stroke
				(width 0.1)
				(type default)
			)
			(layer "F.Fab")
		)
		(pad "1" smd circle
			(at -0.40005 0 90)
			(size 0 0)
			(layers "F.Cu" "F.Mask" "F.Paste")
			(net "PVCCIN_CPU1")
		)
		(pad "2" smd circle
			(at 0.40005 0 90)
			(size 0 0)
			(layers "F.Cu" "F.Mask" "F.Paste")
			(net "GND")
		)
	)
	(footprint ""
		(layer "F.Cu")
		(at 448.787012 -62.020196 -90)
		(property "Reference" "PL66"
			(at -3.292602 -7.236968 0)
			(unlocked yes)
			(layer "F.SilkS")
			(effects
				(font
					(size 0.7874 0.5842)
					(thickness 0.1524)
				)
				(justify left)
			)
		)
		(property "Value" ""
			(at 0 0 270)
			(layer "F.Fab")
			(effects
				(font
					(size 1.27 1.27)
				)
			)
		)
		(duplicate_pad_numbers_are_jumpers no)
		(fp_line
			(start -7.1501 6.450076)
			(end -7.1501 2.6416)
			(stroke
				(width 0.1524)
				(type default)
			)
			(layer "F.SilkS")
		)
		(fp_line
			(start 7.1501 6.450076)
			(end -7.1501 6.450076)
			(stroke
				(width 0.1524)
				(type default)
			)
			(layer "F.SilkS")
		)
		(fp_line
			(start 7.1501 2.6416)
			(end 7.1501 6.450076)
			(stroke
				(width 0.1524)
				(type default)
			)
			(layer "F.SilkS")
		)
		(fp_line
			(start 7.1501 -2.6416)
			(end 7.1501 -6.450076)
			(stroke
				(width 0.1524)
				(type default)
			)
			(layer "F.SilkS")
		)
		(fp_line
			(start -7.1501 -6.450076)
			(end -7.1501 -2.6416)
			(stroke
				(width 0.1524)
				(type default)
			)
			(layer "F.SilkS")
		)
		(fp_line
			(start 7.1501 -6.450076)
			(end -7.1501 -6.450076)
			(stroke
				(width 0.1524)
				(type default)
			)
			(layer "F.SilkS")
		)
		(fp_line
			(start -7.1501 6.450076)
			(end 7.1501 6.450076)
			(stroke
				(width 0.1)
				(type default)
			)
			(layer "F.Fab")
		)
		(fp_line
			(start 7.1501 6.450076)
			(end 7.1501 -6.450076)
			(stroke
				(width 0.1)
				(type default)
			)
			(layer "F.Fab")
		)
		(fp_line
			(start -7.1501 -6.450076)
			(end -7.1501 6.450076)
			(stroke
				(width 0.1)
				(type default)
			)
			(layer "F.Fab")
		)
		(fp_line
			(start 7.1501 -6.450076)
			(end -7.1501 -6.450076)
			(stroke
				(width 0.1)
				(type default)
			)
			(layer "F.Fab")
		)
		(pad "1" smd rect
			(at -5.625084 0 270)
			(size 3.2512 5.0038)
			(layers "F.Cu" "F.Mask" "F.Paste")
			(net "SW_P3V3_AUX_SW")
		)
		(pad "2" smd rect
			(at 5.625084 0 270)
			(size 3.2512 5.0038)
			(layers "F.Cu" "F.Mask" "F.Paste")
			(net "P3V3_AUX")
		)
	)
)
